(kicad_pcb
	(version 20260206)
	(generator "pcbnew")
	(generator_version "10.0")
	(general
		(thickness 1.6)
		(legacy_teardrops no)
	)
	(paper "A4")
	(title_block
		(title "01162023_DA0F0TEBIF0_F0T_Expander_BD_F_brd_V02_OCP.brd")
		(comment 1 "Grand Teton / footprints 8300-8308 of 9728")
	)
	(layers
		(0 "F.Cu" signal "TOP")
		(4 "In1.Cu" signal "GND")
		(6 "In2.Cu" signal "VCC")
		(8 "In3.Cu" signal "VCC1")
		(10 "In4.Cu" signal "GND1")
		(12 "In5.Cu" signal "IN1")
		(14 "In6.Cu" signal "GND2")
		(16 "In7.Cu" signal "IN2")
		(18 "In8.Cu" signal "GND3")
		(20 "In9.Cu" signal "IN3")
		(22 "In10.Cu" signal "GND4")
		(24 "In11.Cu" signal "IN4")
		(26 "In12.Cu" signal "GND5")
		(28 "In13.Cu" signal "IN5")
		(30 "In14.Cu" signal "GND6")
		(32 "In15.Cu" signal "IN6")
		(34 "In16.Cu" signal "GND7")
		(2 "B.Cu" signal "BOTTOM")
		(9 "F.Adhes" user "F.Adhesive")
		(11 "B.Adhes" user "B.Adhesive")
		(13 "F.Paste" user "Package Geometry/Pastemask Top")
		(15 "B.Paste" user "Package Geometry/Pastemask Bottom")
		(5 "F.SilkS" user "Ref Des/Silkscreen Top")
		(7 "B.SilkS" user "Ref Des/Silkscreen Bottom")
		(1 "F.Mask" user "Board Geometry/Soldermask Top")
		(3 "B.Mask" user "Board Geometry/Soldermask Bottom")
		(17 "Dwgs.User" user "User.Drawings")
		(19 "Cmts.User" user "User.Comments")
		(21 "Eco1.User" user "User.Eco1")
		(23 "Eco2.User" user "User.Eco2")
		(25 "Edge.Cuts" user "Board Geometry/Outline")
		(27 "Margin" user)
		(31 "F.CrtYd" user "Package Geometry/Place Bound Top")
		(29 "B.CrtYd" user "Package Geometry/Place Bound Bottom")
		(35 "F.Fab" user "Ref Des/Assembly Top")
		(33 "B.Fab" user "Ref Des/Assembly Bottom")
	)
	(footprint ""
		(layer "B.Cu")
		(at 190.126874 -301.124874 -90)
		(property "Reference" "R1311"
			(at 0 0 90)
			(layer "B.SilkS")
			(hide yes)
			(effects
				(font
					(size 1.27 1.27)
				)
				(justify mirror)
			)
		)
		(property "Value" ""
			(at 0 0 90)
			(layer "B.Fab")
			(effects
				(font
					(size 1.27 1.27)
				)
				(justify mirror)
			)
		)
		(duplicate_pad_numbers_are_jumpers no)
		(fp_line
			(start -0.7874 0.4064)
			(end 0.7874 0.4064)
			(stroke
				(width 0.1524)
				(type default)
			)
			(layer "B.SilkS")
		)
		(fp_line
			(start 0.7874 0.4064)
			(end 0.7874 -0.4064)
			(stroke
				(width 0.1524)
				(type default)
			)
			(layer "B.SilkS")
		)
		(fp_line
			(start -0.7874 -0.4064)
			(end -0.7874 0.4064)
			(stroke
				(width 0.1524)
				(type default)
			)
			(layer "B.SilkS")
		)
		(fp_line
			(start 0.7874 -0.4064)
			(end -0.7874 -0.4064)
			(stroke
				(width 0.1524)
				(type default)
			)
			(layer "B.SilkS")
		)
		(fp_line
			(start -0.67945 0.3048)
			(end -0.120396 0.3048)
			(stroke
				(width 0.1)
				(type default)
			)
			(layer "B.Fab")
		)
		(fp_line
			(start -0.120396 0.3048)
			(end -0.120396 0.2794)
			(stroke
				(width 0.1)
				(type default)
			)
			(layer "B.Fab")
		)
		(fp_line
			(start 0.12065 0.3048)
			(end 0.67945 0.3048)
			(stroke
				(width 0.1)
				(type default)
			)
			(layer "B.Fab")
		)
		(fp_line
			(start 0.67945 0.3048)
			(end 0.67945 -0.305054)
			(stroke
				(width 0.1)
				(type default)
			)
			(layer "B.Fab")
		)
		(fp_line
			(start -0.120396 0.2794)
			(end 0.12065 0.2794)
			(stroke
				(width 0.1)
				(type default)
			)
			(layer "B.Fab")
		)
		(fp_line
			(start 0.12065 0.2794)
			(end 0.12065 0.3048)
			(stroke
				(width 0.1)
				(type default)
			)
			(layer "B.Fab")
		)
		(fp_line
			(start -0.12065 -0.2794)
			(end -0.12065 -0.3048)
			(stroke
				(width 0.1)
				(type default)
			)
			(layer "B.Fab")
		)
		(fp_line
			(start 0.12065 -0.2794)
			(end -0.12065 -0.2794)
			(stroke
				(width 0.1)
				(type default)
			)
			(layer "B.Fab")
		)
		(fp_line
			(start -0.67945 -0.3048)
			(end -0.67945 0.3048)
			(stroke
				(width 0.1)
				(type default)
			)
			(layer "B.Fab")
		)
		(fp_line
			(start -0.12065 -0.3048)
			(end -0.67945 -0.3048)
			(stroke
				(width 0.1)
				(type default)
			)
			(layer "B.Fab")
		)
		(fp_line
			(start 0.12065 -0.305054)
			(end 0.12065 -0.2794)
			(stroke
				(width 0.1)
				(type default)
			)
			(layer "B.Fab")
		)
		(fp_line
			(start 0.67945 -0.305054)
			(end 0.12065 -0.305054)
			(stroke
				(width 0.1)
				(type default)
			)
			(layer "B.Fab")
		)
		(pad "1" smd circle
			(at 0.40005 0 90)
			(size 0 0)
			(layers "B.Cu" "B.Mask" "B.Paste")
			(net "PEX1_ADCTEMP_VINP0")
		)
		(pad "2" smd circle
			(at -0.40005 0 90)
			(size 0 0)
			(layers "B.Cu" "B.Mask" "B.Paste")
			(net "GND")
		)
	)
	(footprint ""
		(layer "B.Cu")
		(at 278.554942 -292.57498)
		(property "Reference" "C3404"
			(at 0 0 0)
			(layer "B.SilkS")
			(hide yes)
			(effects
				(font
					(size 1.27 1.27)
				)
				(justify mirror)
			)
		)
		(property "Value" ""
			(at 0 0 0)
			(layer "B.Fab")
			(effects
				(font
					(size 1.27 1.27)
				)
				(justify mirror)
			)
		)
		(duplicate_pad_numbers_are_jumpers no)
		(fp_line
			(start -0.299974 -0.150114)
			(end -0.299974 0.150114)
			(stroke
				(width 0.1)
				(type default)
			)
			(layer "B.Fab")
		)
		(fp_line
			(start -0.299974 0.150114)
			(end 0.299974 0.150114)
			(stroke
				(width 0.1)
				(type default)
			)
			(layer "B.Fab")
		)
		(fp_line
			(start 0.299974 -0.150114)
			(end -0.299974 -0.150114)
			(stroke
				(width 0.1)
				(type default)
			)
			(layer "B.Fab")
		)
		(fp_line
			(start 0.299974 0.150114)
			(end 0.299974 -0.150114)
			(stroke
				(width 0.1)
				(type default)
			)
			(layer "B.Fab")
		)
		(pad "1" smd rect
			(at 0.2667 0 180)
			(size 0.3048 0.381)
			(layers "B.Cu" "B.Mask" "B.Paste")
			(net "PCEPLL6_VDDA18_PEX2")
		)
		(pad "2" smd rect
			(at -0.2667 0 180)
			(size 0.3048 0.381)
			(layers "B.Cu" "B.Mask" "B.Paste")
			(net "GND")
		)
	)
	(footprint ""
		(layer "B.Cu")
		(at 340.923372 -285.569152 -90)
		(property "Reference" "PR7180"
			(at 0 0 90)
			(layer "B.SilkS")
			(hide yes)
			(effects
				(font
					(size 1.27 1.27)
				)
				(justify mirror)
			)
		)
		(property "Value" ""
			(at 0 0 90)
			(layer "B.Fab")
			(effects
				(font
					(size 1.27 1.27)
				)
				(justify mirror)
			)
		)
		(duplicate_pad_numbers_are_jumpers no)
		(fp_line
			(start -0.7874 0.4064)
			(end 0.7874 0.4064)
			(stroke
				(width 0.1524)
				(type default)
			)
			(layer "B.SilkS")
		)
		(fp_line
			(start 0.7874 0.4064)
			(end 0.7874 -0.4064)
			(stroke
				(width 0.1524)
				(type default)
			)
			(layer "B.SilkS")
		)
		(fp_line
			(start -0.7874 -0.4064)
			(end -0.7874 0.4064)
			(stroke
				(width 0.1524)
				(type default)
			)
			(layer "B.SilkS")
		)
		(fp_line
			(start 0.7874 -0.4064)
			(end -0.7874 -0.4064)
			(stroke
				(width 0.1524)
				(type default)
			)
			(layer "B.SilkS")
		)
		(fp_line
			(start -0.67945 0.3048)
			(end -0.120396 0.3048)
			(stroke
				(width 0.1)
				(type default)
			)
			(layer "B.Fab")
		)
		(fp_line
			(start -0.120396 0.3048)
			(end -0.120396 0.2794)
			(stroke
				(width 0.1)
				(type default)
			)
			(layer "B.Fab")
		)
		(fp_line
			(start 0.12065 0.3048)
			(end 0.67945 0.3048)
			(stroke
				(width 0.1)
				(type default)
			)
			(layer "B.Fab")
		)
		(fp_line
			(start 0.67945 0.3048)
			(end 0.67945 -0.305054)
			(stroke
				(width 0.1)
				(type default)
			)
			(layer "B.Fab")
		)
		(fp_line
			(start -0.120396 0.2794)
			(end 0.12065 0.2794)
			(stroke
				(width 0.1)
				(type default)
			)
			(layer "B.Fab")
		)
		(fp_line
			(start 0.12065 0.2794)
			(end 0.12065 0.3048)
			(stroke
				(width 0.1)
				(type default)
			)
			(layer "B.Fab")
		)
		(fp_line
			(start -0.12065 -0.2794)
			(end -0.12065 -0.3048)
			(stroke
				(width 0.1)
				(type default)
			)
			(layer "B.Fab")
		)
		(fp_line
			(start 0.12065 -0.2794)
			(end -0.12065 -0.2794)
			(stroke
				(width 0.1)
				(type default)
			)
			(layer "B.Fab")
		)
		(fp_line
			(start -0.67945 -0.3048)
			(end -0.67945 0.3048)
			(stroke
				(width 0.1)
				(type default)
			)
			(layer "B.Fab")
		)
		(fp_line
			(start -0.12065 -0.3048)
			(end -0.67945 -0.3048)
			(stroke
				(width 0.1)
				(type default)
			)
			(layer "B.Fab")
		)
		(fp_line
			(start 0.12065 -0.305054)
			(end 0.12065 -0.2794)
			(stroke
				(width 0.1)
				(type default)
			)
			(layer "B.Fab")
		)
		(fp_line
			(start 0.67945 -0.305054)
			(end 0.12065 -0.305054)
			(stroke
				(width 0.1)
				(type default)
			)
			(layer "B.Fab")
		)
		(pad "1" smd circle
			(at 0.40005 0 90)
			(size 0 0)
			(layers "B.Cu" "B.Mask" "B.Paste")
			(net "P0V8_PEX2_PVCC")
		)
		(pad "2" smd circle
			(at -0.40005 0 90)
			(size 0 0)
			(layers "B.Cu" "B.Mask" "B.Paste")
			(net "P5V_AUX")
		)
	)
	(footprint ""
		(layer "B.Cu")
		(at 170.999912 -290.199826 90)
		(property "Reference" "C1453"
			(at 0 0 90)
			(layer "B.SilkS")
			(hide yes)
			(effects
				(font
					(size 1.27 1.27)
				)
				(justify mirror)
			)
		)
		(property "Value" ""
			(at 0 0 90)
			(layer "B.Fab")
			(effects
				(font
					(size 1.27 1.27)
				)
				(justify mirror)
			)
		)
		(duplicate_pad_numbers_are_jumpers no)
		(fp_line
			(start 0.299974 -0.150114)
			(end -0.299974 -0.150114)
			(stroke
				(width 0.1)
				(type default)
			)
			(layer "B.Fab")
		)
		(fp_line
			(start -0.299974 -0.150114)
			(end -0.299974 0.150114)
			(stroke
				(width 0.1)
				(type default)
			)
			(layer "B.Fab")
		)
		(fp_line
			(start 0.299974 0.150114)
			(end 0.299974 -0.150114)
			(stroke
				(width 0.1)
				(type default)
			)
			(layer "B.Fab")
		)
		(fp_line
			(start -0.299974 0.150114)
			(end 0.299974 0.150114)
			(stroke
				(width 0.1)
				(type default)
			)
			(layer "B.Fab")
		)
		(pad "1" smd rect
			(at 0.2667 0 270)
			(size 0.3048 0.381)
			(layers "B.Cu" "B.Mask" "B.Paste")
			(net "P0V8_SERDES_VDDA_PEX1")
		)
		(pad "2" smd rect
			(at -0.2667 0 270)
			(size 0.3048 0.381)
			(layers "B.Cu" "B.Mask" "B.Paste")
			(net "GND")
		)
	)
	(footprint ""
		(layer "B.Cu")
		(at 357.887524 -260.160516)
		(property "Reference" "PR7142"
			(at 0 0 0)
			(layer "B.SilkS")
			(hide yes)
			(effects
				(font
					(size 1.27 1.27)
				)
				(justify mirror)
			)
		)
		(property "Value" ""
			(at 0 0 0)
			(layer "B.Fab")
			(effects
				(font
					(size 1.27 1.27)
				)
				(justify mirror)
			)
		)
		(duplicate_pad_numbers_are_jumpers no)
		(fp_line
			(start -0.7874 -0.4064)
			(end -0.7874 0.4064)
			(stroke
				(width 0.1524)
				(type default)
			)
			(layer "B.SilkS")
		)
		(fp_line
			(start -0.7874 0.4064)
			(end 0.7874 0.4064)
			(stroke
				(width 0.1524)
				(type default)
			)
			(layer "B.SilkS")
		)
		(fp_line
			(start 0.7874 -0.4064)
			(end -0.7874 -0.4064)
			(stroke
				(width 0.1524)
				(type default)
			)
			(layer "B.SilkS")
		)
		(fp_line
			(start 0.7874 0.4064)
			(end 0.7874 -0.4064)
			(stroke
				(width 0.1524)
				(type default)
			)
			(layer "B.SilkS")
		)
		(fp_line
			(start -0.67945 -0.3048)
			(end -0.67945 0.3048)
			(stroke
				(width 0.1)
				(type default)
			)
			(layer "B.Fab")
		)
		(fp_line
			(start -0.67945 0.3048)
			(end -0.120396 0.3048)
			(stroke
				(width 0.1)
				(type default)
			)
			(layer "B.Fab")
		)
		(fp_line
			(start -0.12065 -0.3048)
			(end -0.67945 -0.3048)
			(stroke
				(width 0.1)
				(type default)
			)
			(layer "B.Fab")
		)
		(fp_line
			(start -0.12065 -0.2794)
			(end -0.12065 -0.3048)
			(stroke
				(width 0.1)
				(type default)
			)
			(layer "B.Fab")
		)
		(fp_line
			(start -0.120396 0.2794)
			(end 0.12065 0.2794)
			(stroke
				(width 0.1)
				(type default)
			)
			(layer "B.Fab")
		)
		(fp_line
			(start -0.120396 0.3048)
			(end -0.120396 0.2794)
			(stroke
				(width 0.1)
				(type default)
			)
			(layer "B.Fab")
		)
		(fp_line
			(start 0.12065 -0.305054)
			(end 0.12065 -0.2794)
			(stroke
				(width 0.1)
				(type default)
			)
			(layer "B.Fab")
		)
		(fp_line
			(start 0.12065 -0.2794)
			(end -0.12065 -0.2794)
			(stroke
				(width 0.1)
				(type default)
			)
			(layer "B.Fab")
		)
		(fp_line
			(start 0.12065 0.2794)
			(end 0.12065 0.3048)
			(stroke
				(width 0.1)
				(type default)
			)
			(layer "B.Fab")
		)
		(fp_line
			(start 0.12065 0.3048)
			(end 0.67945 0.3048)
			(stroke
				(width 0.1)
				(type default)
			)
			(layer "B.Fab")
		)
		(fp_line
			(start 0.67945 -0.305054)
			(end 0.12065 -0.305054)
			(stroke
				(width 0.1)
				(type default)
			)
			(layer "B.Fab")
		)
		(fp_line
			(start 0.67945 0.3048)
			(end 0.67945 -0.305054)
			(stroke
				(width 0.1)
				(type default)
			)
			(layer "B.Fab")
		)
		(pad "1" smd circle
			(at 0.40005 0 180)
			(size 0 0)
			(layers "B.Cu" "B.Mask" "B.Paste")
			(net "P0V8_PEX2_VREF")
		)
		(pad "2" smd circle
			(at -0.40005 0 180)
			(size 0 0)
			(layers "B.Cu" "B.Mask" "B.Paste")
			(net "P0V8_PEX2_SVID")
		)
	)
	(footprint ""
		(layer "B.Cu")
		(at 233.467656 -216.704164 180)
		(property "Reference" "C3607"
			(at 0 0 0)
			(layer "B.SilkS")
			(hide yes)
			(effects
				(font
					(size 1.27 1.27)
				)
				(justify mirror)
			)
		)
		(property "Value" ""
			(at 0 0 0)
			(layer "B.Fab")
			(effects
				(font
					(size 1.27 1.27)
				)
				(justify mirror)
			)
		)
		(duplicate_pad_numbers_are_jumpers no)
		(fp_line
			(start 0.69215 0.2921)
			(end 0.69215 -0.2921)
			(stroke
				(width 0.1524)
				(type default)
			)
			(layer "B.SilkS")
		)
		(fp_line
			(start 0.69215 -0.2921)
			(end -0.69215 -0.2921)
			(stroke
				(width 0.1524)
				(type default)
			)
			(layer "B.SilkS")
		)
		(fp_line
			(start -0.69215 0.2921)
			(end 0.69215 0.2921)
			(stroke
				(width 0.1524)
				(type default)
			)
			(layer "B.SilkS")
		)
		(fp_line
			(start -0.69215 -0.2921)
			(end -0.69215 0.2921)
			(stroke
				(width 0.1524)
				(type default)
			)
			(layer "B.SilkS")
		)
		(fp_line
			(start 0.51435 0.2794)
			(end 0.51435 -0.2794)
			(stroke
				(width 0.1)
				(type default)
			)
			(layer "B.Fab")
		)
		(fp_line
			(start 0.51435 -0.2794)
			(end -0.51435 -0.2794)
			(stroke
				(width 0.1)
				(type default)
			)
			(layer "B.Fab")
		)
		(fp_line
			(start -0.51435 0.2794)
			(end 0.51435 0.2794)
			(stroke
				(width 0.1)
				(type default)
			)
			(layer "B.Fab")
		)
		(fp_line
			(start -0.51435 -0.2794)
			(end -0.51435 0.2794)
			(stroke
				(width 0.1)
				(type default)
			)
			(layer "B.Fab")
		)
		(pad "1" smd circle
			(at 0.40005 0)
			(size 0 0)
			(layers "B.Cu" "B.Mask" "B.Paste")
			(net "P3V3_BIC_USB2AV33")
		)
		(pad "2" smd circle
			(at -0.40005 0)
			(size 0 0)
			(layers "B.Cu" "B.Mask" "B.Paste")
			(net "GND")
		)
		(zone
			(layer "B.Cu")
			(hatch none 0.5)
			(connect_pads
				(clearance 0)
			)
			(min_thickness 0.25)
			(keepout
				(tracks not_allowed)
				(vias allowed)
				(pads allowed)
				(copperpour not_allowed)
				(footprints allowed)
			)
			(placement
				(enabled no)
				(sheetname "")
			)
			(fill
				(thermal_gap 0.5)
				(thermal_bridge_width 0.5)
				(island_removal_mode 0)
			)
			(polygon
				(pts
					(xy 233.277156 -216.791794) (xy 233.368596 -216.84996) (xy 233.567986 -216.84996) (xy 233.658156 -216.791794)
					(xy 233.658156 -216.616534) (xy 233.567986 -216.558114) (xy 233.368596 -216.558114) (xy 233.277156 -216.61628)
				)
			)
		)
	)
	(footprint ""
		(layer "B.Cu")
		(at 176.699926 -288.299906 90)
		(property "Reference" "C3107"
			(at 0 0 90)
			(layer "B.SilkS")
			(hide yes)
			(effects
				(font
					(size 1.27 1.27)
				)
				(justify mirror)
			)
		)
		(property "Value" ""
			(at 0 0 90)
			(layer "B.Fab")
			(effects
				(font
					(size 1.27 1.27)
				)
				(justify mirror)
			)
		)
		(duplicate_pad_numbers_are_jumpers no)
		(fp_line
			(start 0.299974 -0.150114)
			(end -0.299974 -0.150114)
			(stroke
				(width 0.1)
				(type default)
			)
			(layer "B.Fab")
		)
		(fp_line
			(start -0.299974 -0.150114)
			(end -0.299974 0.150114)
			(stroke
				(width 0.1)
				(type default)
			)
			(layer "B.Fab")
		)
		(fp_line
			(start 0.299974 0.150114)
			(end 0.299974 -0.150114)
			(stroke
				(width 0.1)
				(type default)
			)
			(layer "B.Fab")
		)
		(fp_line
			(start -0.299974 0.150114)
			(end 0.299974 0.150114)
			(stroke
				(width 0.1)
				(type default)
			)
			(layer "B.Fab")
		)
		(pad "1" smd rect
			(at 0.2667 0 270)
			(size 0.3048 0.381)
			(layers "B.Cu" "B.Mask" "B.Paste")
			(net "P1V25_PEX1")
		)
		(pad "2" smd rect
			(at -0.2667 0 270)
			(size 0.3048 0.381)
			(layers "B.Cu" "B.Mask" "B.Paste")
			(net "GND")
		)
	)
	(footprint ""
		(layer "B.Cu")
		(at 233.867706 -218.70416 -90)
		(property "Reference" "C2006"
			(at 0 0 90)
			(layer "B.SilkS")
			(hide yes)
			(effects
				(font
					(size 1.27 1.27)
				)
				(justify mirror)
			)
		)
		(property "Value" ""
			(at 0 0 90)
			(layer "B.Fab")
			(effects
				(font
					(size 1.27 1.27)
				)
				(justify mirror)
			)
		)
		(duplicate_pad_numbers_are_jumpers no)
		(fp_line
			(start -0.69215 0.2921)
			(end 0.69215 0.2921)
			(stroke
				(width 0.1524)
				(type default)
			)
			(layer "B.SilkS")
		)
		(fp_line
			(start 0.69215 0.2921)
			(end 0.69215 -0.2921)
			(stroke
				(width 0.1524)
				(type default)
			)
			(layer "B.SilkS")
		)
		(fp_line
			(start -0.69215 -0.2921)
			(end -0.69215 0.2921)
			(stroke
				(width 0.1524)
				(type default)
			)
			(layer "B.SilkS")
		)
		(fp_line
			(start 0.69215 -0.2921)
			(end -0.69215 -0.2921)
			(stroke
				(width 0.1524)
				(type default)
			)
			(layer "B.SilkS")
		)
		(fp_line
			(start -0.51435 0.2794)
			(end 0.51435 0.2794)
			(stroke
				(width 0.1)
				(type default)
			)
			(layer "B.Fab")
		)
		(fp_line
			(start 0.51435 0.2794)
			(end 0.51435 -0.2794)
			(stroke
				(width 0.1)
				(type default)
			)
			(layer "B.Fab")
		)
		(fp_line
			(start -0.51435 -0.2794)
			(end -0.51435 0.2794)
			(stroke
				(width 0.1)
				(type default)
			)
			(layer "B.Fab")
		)
		(fp_line
			(start 0.51435 -0.2794)
			(end -0.51435 -0.2794)
			(stroke
				(width 0.1)
				(type default)
			)
			(layer "B.Fab")
		)
		(pad "1" smd circle
			(at 0.40005 0 90)
			(size 0 0)
			(layers "B.Cu" "B.Mask" "B.Paste")
			(net "P3V3_AUX")
		)
		(pad "2" smd circle
			(at -0.40005 0 90)
			(size 0 0)
			(layers "B.Cu" "B.Mask" "B.Paste")
			(net "GND")
		)
		(zone
			(layer "B.Cu")
			(hatch none 0.5)
			(connect_pads
				(clearance 0)
			)
			(min_thickness 0.25)
			(keepout
				(tracks not_allowed)
				(vias allowed)
				(pads allowed)
				(copperpour not_allowed)
				(footprints allowed)
			)
			(placement
				(enabled no)
				(sheetname "")
			)
			(fill
				(thermal_gap 0.5)
				(thermal_bridge_width 0.5)
				(island_removal_mode 0)
			)
			(polygon
				(pts
					(xy 233.780076 -218.51366) (xy 233.72191 -218.6051) (xy 233.72191 -218.80449) (xy 233.780076 -218.89466)
					(xy 233.955336 -218.89466) (xy 234.013756 -218.80449) (xy 234.013756 -218.6051) (xy 233.95559 -218.51366)
				)
			)
		)
	)
	(footprint ""
		(layer "B.Cu")
		(at 407.949908 -290.199826 90)
		(property "Reference" "C2000"
			(at 0 0 90)
			(layer "B.SilkS")
			(hide yes)
			(effects
				(font
					(size 1.27 1.27)
				)
				(justify mirror)
			)
		)
		(property "Value" ""
			(at 0 0 90)
			(layer "B.Fab")
			(effects
				(font
					(size 1.27 1.27)
				)
				(justify mirror)
			)
		)
		(duplicate_pad_numbers_are_jumpers no)
		(fp_line
			(start 0.299974 -0.150114)
			(end -0.299974 -0.150114)
			(stroke
				(width 0.1)
				(type default)
			)
			(layer "B.Fab")
		)
		(fp_line
			(start -0.299974 -0.150114)
			(end -0.299974 0.150114)
			(stroke
				(width 0.1)
				(type default)
			)
			(layer "B.Fab")
		)
		(fp_line
			(start 0.299974 0.150114)
			(end 0.299974 -0.150114)
			(stroke
				(width 0.1)
				(type default)
			)
			(layer "B.Fab")
		)
		(fp_line
			(start -0.299974 0.150114)
			(end 0.299974 0.150114)
			(stroke
				(width 0.1)
				(type default)
			)
			(layer "B.Fab")
		)
		(pad "1" smd rect
			(at 0.2667 0 270)
			(size 0.3048 0.381)
			(layers "B.Cu" "B.Mask" "B.Paste")
			(net "P0V8_SERDES_VDDA_PEX3")
		)
		(pad "2" smd rect
			(at -0.2667 0 270)
			(size 0.3048 0.381)
			(layers "B.Cu" "B.Mask" "B.Paste")
			(net "GND")
		)
	)
)
